#ISCELL
  mstr_misc dns *
  *
#ISCELL
  pure_quanta quanta_title_block_c *
  *
#ISCELL
  pure_quanta_power gnd *
  page245_i1
#CELL
  pure_quanta q_res *
  page245_i10
#CELL
  pure_quanta q_res *
  page245_i11
#CELL
  pure_quanta q_cap *
  page245_i12
#ISCELL
  pure_quanta_power gnd *
  page245_i13
#ISCELL
  pure_quanta_power gnd *
  page245_i14
#CELL
  pure_quanta q_res *
  page245_i15
#ISCELL
  pure_quanta_power gnd *
  page245_i16
#CELL
  pure_quanta q_res *
  page245_i17
#ISCELL
  pure_quanta_power gnd *
  page245_i18
#CELL
  pure_quanta q_cap *
  page245_i19
#CELL
  pure_quanta q_res *
  page245_i2
#CELL
  pure_quanta q_res *
  page245_i20
#CELL
  pure_quanta ncp3284amntxg *
  page245_i21
#ISCELL
  pure_quanta_power gnd *
  page245_i22
#CELL
  pure_quanta q_cap *
  page245_i23
#CELL
  pure_quanta q_inductor *
  page245_i24
#ISCELL
  pure_quanta_power universal_power *
  page245_i25
#CELL
  pure_quanta q_cap *
  page245_i26
#CELL
  pure_quanta q_cap *
  page245_i27
#ISCELL
  pure_quanta_power gnd *
  page245_i28
#CELL
  pure_quanta q_capp *
  page245_i29
#ISCELL
  pure_quanta_power gnd *
  page245_i3
#CELL
  pure_quanta q_capp *
  page245_i30
#CELL
  pure_quanta q_cap *
  page245_i31
#CELL
  pure_quanta q_cap *
  page245_i32
#CELL
  pure_quanta q_cap *
  page245_i33
#CELL
  pure_quanta q_cap *
  page245_i34
#CELL
  pure_quanta q_cap *
  page245_i35
#CELL
  pure_quanta q_cap *
  page245_i36
#CELL
  pure_quanta q_cap *
  page245_i37
#CELL
  pure_quanta q_cap *
  page245_i38
#CELL
  pure_quanta q_cap *
  page245_i39
#CELL
  pure_quanta q_res *
  page245_i4
#CELL
  pure_quanta q_cap *
  page245_i40
#CELL
  pure_quanta q_cap *
  page245_i41
#ISCELL
  pure_quanta_power universal_power *
  page245_i42
#ISCELL
  pure_quanta_power gnd *
  page245_i43
#CELL
  pure_quanta q_cap *
  page245_i44
#ISCELL
  pure_quanta_power gnd *
  page245_i45
#CELL
  pure_quanta q_res *
  page245_i46
#ISCELL
  pure_quanta_power gnd *
  page245_i47
#CELL
  pure_quanta q_cap *
  page245_i48
#CELL
  pure_quanta q_res *
  page245_i49
#ISCELL
  standard offpage *
  page245_i5
#ISCELL
  pure_quanta_power gnd *
  page245_i50
#CELL
  pure_quanta q_res *
  page245_i51
#ISCELL
  pure_quanta_power universal_power *
  page245_i52
#CELL
  pure_quanta q_cap *
  page245_i53
#CELL
  pure_quanta q_res *
  page245_i54
#CELL
  pure_quanta q_inductor *
  page245_i55
#ISCELL
  standard offpage *
  page245_i56
#CELL
  pure_quanta q_capp *
  page245_i57
#CELL
  pure_quanta q_capp *
  page245_i58
#CELL
  pure_quanta q_cap *
  page245_i59
#ISCELL
  pure_quanta_power p1v0_aux *
  page245_i6
#CELL
  pure_quanta q_cap *
  page245_i60
#ISCELL
  pure_quanta_power gnd *
  page245_i61
#CELL
  pure_quanta q_cap *
  page245_i62
#CELL
  pure_quanta q_cap *
  page245_i63
#ISCELL
  pure_quanta_power universal_power *
  page245_i64
#CELL
  pure_quanta q_res *
  page245_i65
#ISCELL
  pure_quanta_power universal_power *
  page245_i66
#CELL
  pure_quanta q_res *
  page245_i67
#CELL
  pure_quanta q_cap *
  page245_i68
#ISCELL
  pure_quanta_power gnd *
  page245_i69
#ISCELL
  pure_quanta_power gnd *
  page245_i7
#CELL
  pure_quanta q_cap *
  page245_i70
#CELL
  pure_quanta q_cap *
  page245_i71
#CELL
  pure_quanta q_cap *
  page245_i8
#ISCELL
  pure_quanta_power gnd *
  page245_i9
